# S9S_MB_2U (Grand Teton) — schematic netlist excerpt (pin names and nets, part order shuffled) for the footprints in the layout excerpt that follows; sources: Cadence DE-HDL packaged netlist, KiCad conversion of 03242023_DA0F0TMBIJ0_F0T_Motherboard_J_brd_V01_OCP.brd

C906  Q_CAP_DIFFBUS  DIFF BUS_0.22UF 6.3V 20% X6S  pkg C0201  page 173 : \1\ = P5E_CPU0_PE0_TX_C_DN<13> ; \2\ = P5E_CPU0_PE0_TX_DN<13>
R4183  Q_RES  33.2 1% CHIP  pkg 0402LF  page 170 : A = SMB_LM75_0_3V3AUX_SDA ; B = SMB_LM75_0_3V3AUX_SDA_R1
R2525  Q_RES  1K 1% CHIP  pkg 0402LF  page 284 : A = P3V3_AUX ; B = PVCCIN_CPU1_PIN_ALERT

(kicad_pcb
	(version 20260206)
	(generator "pcbnew")
	(generator_version "10.0")
	(general
		(thickness 1.6)
		(legacy_teardrops no)
	)
	(paper "A4")
	(title_block
		(title "03242023_DA0F0TMBIJ0_F0T_Motherboard_J_brd_V01_OCP.brd")
		(comment 1 "Grand Teton / footprints 3943-3945 of 6105")
	)
	(layers
		(0 "F.Cu" signal "TOP")
		(4 "In1.Cu" signal "GND")
		(6 "In2.Cu" signal "IN1")
		(8 "In3.Cu" signal "GND1")
		(10 "In4.Cu" signal "IN2")
		(12 "In5.Cu" signal "GND2")
		(14 "In6.Cu" signal "IN3")
		(16 "In7.Cu" signal "GND3")
		(18 "In8.Cu" signal "VCC")
		(20 "In9.Cu" signal "VCC1")
		(22 "In10.Cu" signal "GND4")
		(24 "In11.Cu" signal "IN4")
		(26 "In12.Cu" signal "GND5")
		(28 "In13.Cu" signal "IN5")
		(30 "In14.Cu" signal "GND6")
		(32 "In15.Cu" signal "IN6")
		(34 "In16.Cu" signal "GND7")
		(2 "B.Cu" signal "BOTTOM")
		(9 "F.Adhes" user "F.Adhesive")
		(11 "B.Adhes" user "B.Adhesive")
		(13 "F.Paste" user "Package Geometry/Pastemask Top")
		(15 "B.Paste" user "Package Geometry/Pastemask Bottom")
		(5 "F.SilkS" user "Ref Des/Silkscreen Top")
		(7 "B.SilkS" user "Ref Des/Silkscreen Bottom")
		(1 "F.Mask" user "Board Geometry/Soldermask Top")
		(3 "B.Mask" user "Board Geometry/Soldermask Bottom")
		(17 "Dwgs.User" user "User.Drawings")
		(19 "Cmts.User" user "User.Comments")
		(21 "Eco1.User" user "User.Eco1")
		(23 "Eco2.User" user "User.Eco2")
		(25 "Edge.Cuts" user "Board Geometry/Outline")
		(27 "Margin" user)
		(31 "F.CrtYd" user "Package Geometry/Place Bound Top")
		(29 "B.CrtYd" user "Package Geometry/Place Bound Bottom")
		(35 "F.Fab" user "Ref Des/Assembly Top")
		(33 "B.Fab" user "Ref Des/Assembly Bottom")
	)
	(footprint ""
		(layer "F.Cu")
		(at 366.431322 -425.18457)
		(property "Reference" "R4183"
			(at 0 0 0)
			(layer "F.SilkS")
			(hide yes)
			(effects
				(font
					(size 1.27 1.27)
				)
			)
		)
		(property "Value" ""
			(at 0 0 0)
			(layer "F.Fab")
			(effects
				(font
					(size 1.27 1.27)
				)
			)
		)
		(duplicate_pad_numbers_are_jumpers no)
		(fp_line
			(start -0.7874 -0.4064)
			(end 0.7874 -0.4064)
			(stroke
				(width 0.1524)
				(type default)
			)
			(layer "F.SilkS")
		)
		(fp_line
			(start -0.7874 0.4064)
			(end -0.7874 -0.4064)
			(stroke
				(width 0.1524)
				(type default)
			)
			(layer "F.SilkS")
		)
		(fp_line
			(start 0.7874 -0.4064)
			(end 0.7874 0.4064)
			(stroke
				(width 0.1524)
				(type default)
			)
			(layer "F.SilkS")
		)
		(fp_line
			(start 0.7874 0.4064)
			(end -0.7874 0.4064)
			(stroke
				(width 0.1524)
				(type default)
			)
			(layer "F.SilkS")
		)
		(fp_line
			(start -0.67945 -0.305054)
			(end -0.12065 -0.305054)
			(stroke
				(width 0.1)
				(type default)
			)
			(layer "F.Fab")
		)
		(fp_line
			(start -0.67945 0.3048)
			(end -0.67945 -0.305054)
			(stroke
				(width 0.1)
				(type default)
			)
			(layer "F.Fab")
		)
		(fp_line
			(start -0.12065 -0.305054)
			(end -0.12065 -0.2794)
			(stroke
				(width 0.1)
				(type default)
			)
			(layer "F.Fab")
		)
		(fp_line
			(start -0.12065 -0.2794)
			(end 0.12065 -0.2794)
			(stroke
				(width 0.1)
				(type default)
			)
			(layer "F.Fab")
		)
		(fp_line
			(start -0.12065 0.2794)
			(end -0.12065 0.3048)
			(stroke
				(width 0.1)
				(type default)
			)
			(layer "F.Fab")
		)
		(fp_line
			(start -0.12065 0.3048)
			(end -0.67945 0.3048)
			(stroke
				(width 0.1)
				(type default)
			)
			(layer "F.Fab")
		)
		(fp_line
			(start 0.120396 0.2794)
			(end -0.12065 0.2794)
			(stroke
				(width 0.1)
				(type default)
			)
			(layer "F.Fab")
		)
		(fp_line
			(start 0.120396 0.3048)
			(end 0.120396 0.2794)
			(stroke
				(width 0.1)
				(type default)
			)
			(layer "F.Fab")
		)
		(fp_line
			(start 0.12065 -0.3048)
			(end 0.67945 -0.3048)
			(stroke
				(width 0.1)
				(type default)
			)
			(layer "F.Fab")
		)
		(fp_line
			(start 0.12065 -0.2794)
			(end 0.12065 -0.3048)
			(stroke
				(width 0.1)
				(type default)
			)
			(layer "F.Fab")
		)
		(fp_line
			(start 0.67945 -0.3048)
			(end 0.67945 0.3048)
			(stroke
				(width 0.1)
				(type default)
			)
			(layer "F.Fab")
		)
		(fp_line
			(start 0.67945 0.3048)
			(end 0.120396 0.3048)
			(stroke
				(width 0.1)
				(type default)
			)
			(layer "F.Fab")
		)
		(pad "1" smd circle
			(at -0.40005 0)
			(size 0 0)
			(layers "F.Cu" "F.Mask" "F.Paste")
			(net "SMB_LM75_0_3V3AUX_SDA")
		)
		(pad "2" smd circle
			(at 0.40005 0)
			(size 0 0)
			(layers "F.Cu" "F.Mask" "F.Paste")
			(net "SMB_LM75_0_3V3AUX_SDA_R1")
		)
	)
	(footprint ""
		(layer "F.Cu")
		(at 100.66655 -359.059226)
		(property "Reference" "R2525"
			(at 0 0 0)
			(layer "F.SilkS")
			(hide yes)
			(effects
				(font
					(size 1.27 1.27)
				)
			)
		)
		(property "Value" ""
			(at 0 0 0)
			(layer "F.Fab")
			(effects
				(font
					(size 1.27 1.27)
				)
			)
		)
		(duplicate_pad_numbers_are_jumpers no)
		(fp_line
			(start -0.7874 -0.4064)
			(end 0.7874 -0.4064)
			(stroke
				(width 0.1524)
				(type default)
			)
			(layer "F.SilkS")
		)
		(fp_line
			(start -0.7874 0.4064)
			(end -0.7874 -0.4064)
			(stroke
				(width 0.1524)
				(type default)
			)
			(layer "F.SilkS")
		)
		(fp_line
			(start 0.7874 -0.4064)
			(end 0.7874 0.4064)
			(stroke
				(width 0.1524)
				(type default)
			)
			(layer "F.SilkS")
		)
		(fp_line
			(start 0.7874 0.4064)
			(end -0.7874 0.4064)
			(stroke
				(width 0.1524)
				(type default)
			)
			(layer "F.SilkS")
		)
		(fp_line
			(start -0.67945 -0.305054)
			(end -0.12065 -0.305054)
			(stroke
				(width 0.1)
				(type default)
			)
			(layer "F.Fab")
		)
		(fp_line
			(start -0.67945 0.3048)
			(end -0.67945 -0.305054)
			(stroke
				(width 0.1)
				(type default)
			)
			(layer "F.Fab")
		)
		(fp_line
			(start -0.12065 -0.305054)
			(end -0.12065 -0.2794)
			(stroke
				(width 0.1)
				(type default)
			)
			(layer "F.Fab")
		)
		(fp_line
			(start -0.12065 -0.2794)
			(end 0.12065 -0.2794)
			(stroke
				(width 0.1)
				(type default)
			)
			(layer "F.Fab")
		)
		(fp_line
			(start -0.12065 0.2794)
			(end -0.12065 0.3048)
			(stroke
				(width 0.1)
				(type default)
			)
			(layer "F.Fab")
		)
		(fp_line
			(start -0.12065 0.3048)
			(end -0.67945 0.3048)
			(stroke
				(width 0.1)
				(type default)
			)
			(layer "F.Fab")
		)
		(fp_line
			(start 0.120396 0.2794)
			(end -0.12065 0.2794)
			(stroke
				(width 0.1)
				(type default)
			)
			(layer "F.Fab")
		)
		(fp_line
			(start 0.120396 0.3048)
			(end 0.120396 0.2794)
			(stroke
				(width 0.1)
				(type default)
			)
			(layer "F.Fab")
		)
		(fp_line
			(start 0.12065 -0.3048)
			(end 0.67945 -0.3048)
			(stroke
				(width 0.1)
				(type default)
			)
			(layer "F.Fab")
		)
		(fp_line
			(start 0.12065 -0.2794)
			(end 0.12065 -0.3048)
			(stroke
				(width 0.1)
				(type default)
			)
			(layer "F.Fab")
		)
		(fp_line
			(start 0.67945 -0.3048)
			(end 0.67945 0.3048)
			(stroke
				(width 0.1)
				(type default)
			)
			(layer "F.Fab")
		)
		(fp_line
			(start 0.67945 0.3048)
			(end 0.120396 0.3048)
			(stroke
				(width 0.1)
				(type default)
			)
			(layer "F.Fab")
		)
		(pad "1" smd circle
			(at -0.40005 0)
			(size 0 0)
			(layers "F.Cu" "F.Mask" "F.Paste")
			(net "P3V3_AUX")
		)
		(pad "2" smd circle
			(at 0.40005 0)
			(size 0 0)
			(layers "F.Cu" "F.Mask" "F.Paste")
			(net "PVCCIN_CPU1_PIN_ALERT")
		)
	)
	(footprint ""
		(layer "F.Cu")
		(at 311.427368 -408.517344 -90)
		(property "Reference" "C906"
			(at 0 0 270)
			(layer "F.SilkS")
			(hide yes)
			(effects
				(font
					(size 1.27 1.27)
				)
			)
		)
		(property "Value" ""
			(at 0 0 270)
			(layer "F.Fab")
			(effects
				(font
					(size 1.27 1.27)
				)
			)
		)
		(duplicate_pad_numbers_are_jumpers no)
		(fp_line
			(start -0.299974 0.150114)
			(end -0.299974 -0.150114)
			(stroke
				(width 0.1)
				(type default)
			)
			(layer "F.Fab")
		)
		(fp_line
			(start 0.299974 0.150114)
			(end -0.299974 0.150114)
			(stroke
				(width 0.1)
				(type default)
			)
			(layer "F.Fab")
		)
		(fp_line
			(start -0.299974 -0.150114)
			(end 0.299974 -0.150114)
			(stroke
				(width 0.1)
				(type default)
			)
			(layer "F.Fab")
		)
		(fp_line
			(start 0.299974 -0.150114)
			(end 0.299974 0.150114)
			(stroke
				(width 0.1)
				(type default)
			)
			(layer "F.Fab")
		)
		(pad "1" smd rect
			(at -0.2667 0 270)
			(size 0.3048 0.381)
			(layers "F.Cu" "F.Mask" "F.Paste")
			(net "P5E_CPU0_PE0_TX_C_DN<13>")
		)
		(pad "2" smd rect
			(at 0.2667 0 270)
			(size 0.3048 0.381)
			(layers "F.Cu" "F.Mask" "F.Paste")
			(net "P5E_CPU0_PE0_TX_DN<13>")
		)
	)
)
